# T6G (Grand Teton) — schematic netlist excerpt (pin names and nets, part order shuffled) for the footprints in the layout excerpt that follows; sources: Cadence DE-HDL packaged netlist, KiCad conversion of 04192023_DAF0TMB3IC0_F0TG_MB_C_brd_V02_OCP.brd

R495  Q_RES  4.7K 5% CHIP  pkg 0402LF  page 34 : A = PVDD18_S5_P0 ; B = SMB_CPU0_4_SCL
PR197  Q_RES  5.6 1% CHIP  pkg 0402LF  page 212 : A = SW_PVDDCR_CPU0_P1_BOOT3 ; B = SW_PVDDCR_CPU0_P1_BOOT3_RC

(kicad_pcb
	(version 20260206)
	(generator "pcbnew")
	(generator_version "10.0")
	(general
		(thickness 1.6)
		(legacy_teardrops no)
	)
	(paper "A4")
	(title_block
		(title "04192023_DAF0TMB3IC0_F0TG_MB_C_brd_V02_OCP.brd")
		(comment 1 "Grand Teton / footprints 4046-4047 of 8354")
	)
	(layers
		(0 "F.Cu" signal "TOP")
		(4 "In1.Cu" signal "GND")
		(6 "In2.Cu" signal "IN1")
		(8 "In3.Cu" signal "GND1")
		(10 "In4.Cu" signal "IN2")
		(12 "In5.Cu" signal "GND2")
		(14 "In6.Cu" signal "IN3")
		(16 "In7.Cu" signal "GND3")
		(18 "In8.Cu" signal "VCC")
		(20 "In9.Cu" signal "VCC1")
		(22 "In10.Cu" signal "GND4")
		(24 "In11.Cu" signal "IN4")
		(26 "In12.Cu" signal "GND5")
		(28 "In13.Cu" signal "IN5")
		(30 "In14.Cu" signal "GND6")
		(32 "In15.Cu" signal "IN6")
		(34 "In16.Cu" signal "GND7")
		(2 "B.Cu" signal "BOTTOM")
		(9 "F.Adhes" user "F.Adhesive")
		(11 "B.Adhes" user "B.Adhesive")
		(13 "F.Paste" user "Package Geometry/Pastemask Top")
		(15 "B.Paste" user "Package Geometry/Pastemask Bottom")
		(5 "F.SilkS" user "Ref Des/Silkscreen Top")
		(7 "B.SilkS" user "Ref Des/Silkscreen Bottom")
		(1 "F.Mask" user "Board Geometry/Soldermask Top")
		(3 "B.Mask" user "Board Geometry/Soldermask Bottom")
		(17 "Dwgs.User" user "User.Drawings")
		(19 "Cmts.User" user "User.Comments")
		(21 "Eco1.User" user "User.Eco1")
		(23 "Eco2.User" user "User.Eco2")
		(25 "Edge.Cuts" user "Board Geometry/Outline")
		(27 "Margin" user)
		(31 "F.CrtYd" user "Package Geometry/Place Bound Top")
		(29 "B.CrtYd" user "Package Geometry/Place Bound Bottom")
		(35 "F.Fab" user "Ref Des/Assembly Top")
		(33 "B.Fab" user "Ref Des/Assembly Bottom")
	)
	(footprint ""
		(layer "F.Cu")
		(at 98.314764 -178.0413 -90)
		(property "Reference" "PR197"
			(at 0 0 270)
			(layer "F.SilkS")
			(hide yes)
			(effects
				(font
					(size 1.27 1.27)
				)
			)
		)
		(property "Value" ""
			(at 0 0 270)
			(layer "F.Fab")
			(effects
				(font
					(size 1.27 1.27)
				)
			)
		)
		(duplicate_pad_numbers_are_jumpers no)
		(fp_line
			(start -0.7874 0.4064)
			(end -0.7874 -0.4064)
			(stroke
				(width 0.1524)
				(type default)
			)
			(layer "F.SilkS")
		)
		(fp_line
			(start 0.7874 0.4064)
			(end -0.7874 0.4064)
			(stroke
				(width 0.1524)
				(type default)
			)
			(layer "F.SilkS")
		)
		(fp_line
			(start -0.7874 -0.4064)
			(end 0.7874 -0.4064)
			(stroke
				(width 0.1524)
				(type default)
			)
			(layer "F.SilkS")
		)
		(fp_line
			(start 0.7874 -0.4064)
			(end 0.7874 0.4064)
			(stroke
				(width 0.1524)
				(type default)
			)
			(layer "F.SilkS")
		)
		(fp_line
			(start -0.67945 0.3048)
			(end -0.67945 -0.305054)
			(stroke
				(width 0.1)
				(type default)
			)
			(layer "F.Fab")
		)
		(fp_line
			(start -0.12065 0.3048)
			(end -0.67945 0.3048)
			(stroke
				(width 0.1)
				(type default)
			)
			(layer "F.Fab")
		)
		(fp_line
			(start 0.120396 0.3048)
			(end 0.120396 0.2794)
			(stroke
				(width 0.1)
				(type default)
			)
			(layer "F.Fab")
		)
		(fp_line
			(start 0.67945 0.3048)
			(end 0.120396 0.3048)
			(stroke
				(width 0.1)
				(type default)
			)
			(layer "F.Fab")
		)
		(fp_line
			(start -0.12065 0.2794)
			(end -0.12065 0.3048)
			(stroke
				(width 0.1)
				(type default)
			)
			(layer "F.Fab")
		)
		(fp_line
			(start 0.120396 0.2794)
			(end -0.12065 0.2794)
			(stroke
				(width 0.1)
				(type default)
			)
			(layer "F.Fab")
		)
		(fp_line
			(start -0.12065 -0.2794)
			(end 0.12065 -0.2794)
			(stroke
				(width 0.1)
				(type default)
			)
			(layer "F.Fab")
		)
		(fp_line
			(start 0.12065 -0.2794)
			(end 0.12065 -0.3048)
			(stroke
				(width 0.1)
				(type default)
			)
			(layer "F.Fab")
		)
		(fp_line
			(start 0.12065 -0.3048)
			(end 0.67945 -0.3048)
			(stroke
				(width 0.1)
				(type default)
			)
			(layer "F.Fab")
		)
		(fp_line
			(start 0.67945 -0.3048)
			(end 0.67945 0.3048)
			(stroke
				(width 0.1)
				(type default)
			)
			(layer "F.Fab")
		)
		(fp_line
			(start -0.67945 -0.305054)
			(end -0.12065 -0.305054)
			(stroke
				(width 0.1)
				(type default)
			)
			(layer "F.Fab")
		)
		(fp_line
			(start -0.12065 -0.305054)
			(end -0.12065 -0.2794)
			(stroke
				(width 0.1)
				(type default)
			)
			(layer "F.Fab")
		)
		(pad "1" smd circle
			(at -0.40005 0 270)
			(size 0 0)
			(layers "F.Cu" "F.Mask" "F.Paste")
			(net "SW_PVDDCR_CPU0_P1_BOOT3")
		)
		(pad "2" smd circle
			(at 0.40005 0 270)
			(size 0 0)
			(layers "F.Cu" "F.Mask" "F.Paste")
			(net "SW_PVDDCR_CPU0_P1_BOOT3_RC")
		)
	)
	(footprint ""
		(layer "F.Cu")
		(at 178.47183 -157.508194 -90)
		(property "Reference" "R495"
			(at 0 0 270)
			(layer "F.SilkS")
			(hide yes)
			(effects
				(font
					(size 1.27 1.27)
				)
			)
		)
		(property "Value" ""
			(at 0 0 270)
			(layer "F.Fab")
			(effects
				(font
					(size 1.27 1.27)
				)
			)
		)
		(duplicate_pad_numbers_are_jumpers no)
		(fp_line
			(start -0.7874 0.4064)
			(end -0.7874 -0.4064)
			(stroke
				(width 0.1524)
				(type default)
			)
			(layer "F.SilkS")
		)
		(fp_line
			(start 0.7874 0.4064)
			(end -0.7874 0.4064)
			(stroke
				(width 0.1524)
				(type default)
			)
			(layer "F.SilkS")
		)
		(fp_line
			(start -0.7874 -0.4064)
			(end 0.7874 -0.4064)
			(stroke
				(width 0.1524)
				(type default)
			)
			(layer "F.SilkS")
		)
		(fp_line
			(start 0.7874 -0.4064)
			(end 0.7874 0.4064)
			(stroke
				(width 0.1524)
				(type default)
			)
			(layer "F.SilkS")
		)
		(fp_line
			(start -0.67945 0.3048)
			(end -0.67945 -0.305054)
			(stroke
				(width 0.1)
				(type default)
			)
			(layer "F.Fab")
		)
		(fp_line
			(start -0.12065 0.3048)
			(end -0.67945 0.3048)
			(stroke
				(width 0.1)
				(type default)
			)
			(layer "F.Fab")
		)
		(fp_line
			(start 0.120396 0.3048)
			(end 0.120396 0.2794)
			(stroke
				(width 0.1)
				(type default)
			)
			(layer "F.Fab")
		)
		(fp_line
			(start 0.67945 0.3048)
			(end 0.120396 0.3048)
			(stroke
				(width 0.1)
				(type default)
			)
			(layer "F.Fab")
		)
		(fp_line
			(start -0.12065 0.2794)
			(end -0.12065 0.3048)
			(stroke
				(width 0.1)
				(type default)
			)
			(layer "F.Fab")
		)
		(fp_line
			(start 0.120396 0.2794)
			(end -0.12065 0.2794)
			(stroke
				(width 0.1)
				(type default)
			)
			(layer "F.Fab")
		)
		(fp_line
			(start -0.12065 -0.2794)
			(end 0.12065 -0.2794)
			(stroke
				(width 0.1)
				(type default)
			)
			(layer "F.Fab")
		)
		(fp_line
			(start 0.12065 -0.2794)
			(end 0.12065 -0.3048)
			(stroke
				(width 0.1)
				(type default)
			)
			(layer "F.Fab")
		)
		(fp_line
			(start 0.12065 -0.3048)
			(end 0.67945 -0.3048)
			(stroke
				(width 0.1)
				(type default)
			)
			(layer "F.Fab")
		)
		(fp_line
			(start 0.67945 -0.3048)
			(end 0.67945 0.3048)
			(stroke
				(width 0.1)
				(type default)
			)
			(layer "F.Fab")
		)
		(fp_line
			(start -0.67945 -0.305054)
			(end -0.12065 -0.305054)
			(stroke
				(width 0.1)
				(type default)
			)
			(layer "F.Fab")
		)
		(fp_line
			(start -0.12065 -0.305054)
			(end -0.12065 -0.2794)
			(stroke
				(width 0.1)
				(type default)
			)
			(layer "F.Fab")
		)
		(pad "1" smd circle
			(at -0.40005 0 270)
			(size 0 0)
			(layers "F.Cu" "F.Mask" "F.Paste")
			(net "PVDD18_S5_P0")
		)
		(pad "2" smd circle
			(at 0.40005 0 270)
			(size 0 0)
			(layers "F.Cu" "F.Mask" "F.Paste")
			(net "SMB_CPU0_4_SCL")
		)
	)
)
